(kicad_pcb
	(version 20260206)
	(generator "pcbnew")
	(generator_version "10.0")
	(general
		(thickness 1.6)
		(legacy_teardrops no)
	)
	(paper "A4")
	(title_block
		(title "12092022_DA0F0TMDCD0_F0T_Management_Board_D_brd_V3_OCP.brd")
		(comment 1 "Grand Teton / footprints 154-159 of 1440")
	)
	(layers
		(0 "F.Cu" signal "TOP")
		(4 "In1.Cu" signal "GND")
		(6 "In2.Cu" signal "IN1")
		(8 "In3.Cu" signal "GND1")
		(10 "In4.Cu" signal "IN2")
		(12 "In5.Cu" signal "VCC")
		(14 "In6.Cu" signal "VCC1")
		(16 "In7.Cu" signal "IN3")
		(18 "In8.Cu" signal "GND2")
		(20 "In9.Cu" signal "IN4")
		(22 "In10.Cu" signal "GND3")
		(2 "B.Cu" signal "BOTTOM")
		(9 "F.Adhes" user "F.Adhesive")
		(11 "B.Adhes" user "B.Adhesive")
		(13 "F.Paste" user "Package Geometry/Pastemask Top")
		(15 "B.Paste" user "Package Geometry/Pastemask Bottom")
		(5 "F.SilkS" user "Ref Des/Silkscreen Top")
		(7 "B.SilkS" user "Ref Des/Silkscreen Bottom")
		(1 "F.Mask" user "Board Geometry/Soldermask Top")
		(3 "B.Mask" user "Board Geometry/Soldermask Bottom")
		(17 "Dwgs.User" user "User.Drawings")
		(19 "Cmts.User" user "User.Comments")
		(21 "Eco1.User" user "User.Eco1")
		(23 "Eco2.User" user "User.Eco2")
		(25 "Edge.Cuts" user "Board Geometry/Outline")
		(27 "Margin" user)
		(31 "F.CrtYd" user "Package Geometry/Place Bound Top")
		(29 "B.CrtYd" user "Package Geometry/Place Bound Bottom")
		(35 "F.Fab" user "Ref Des/Assembly Top")
		(33 "B.Fab" user "Ref Des/Assembly Bottom")
	)
	(footprint ""
		(layer "F.Cu")
		(at 12.4206 -101.9429)
		(property "Reference" "R463"
			(at 0 0 0)
			(layer "F.SilkS")
			(hide yes)
			(effects
				(font
					(size 1.27 1.27)
				)
			)
		)
		(property "Value" ""
			(at 0 0 0)
			(layer "F.Fab")
			(effects
				(font
					(size 1.27 1.27)
				)
			)
		)
		(duplicate_pad_numbers_are_jumpers no)
		(fp_line
			(start -0.7874 -0.4064)
			(end 0.7874 -0.4064)
			(stroke
				(width 0.1524)
				(type default)
			)
			(layer "F.SilkS")
		)
		(fp_line
			(start -0.7874 0.4064)
			(end -0.7874 -0.4064)
			(stroke
				(width 0.1524)
				(type default)
			)
			(layer "F.SilkS")
		)
		(fp_line
			(start 0.7874 -0.4064)
			(end 0.7874 0.4064)
			(stroke
				(width 0.1524)
				(type default)
			)
			(layer "F.SilkS")
		)
		(fp_line
			(start 0.7874 0.4064)
			(end -0.7874 0.4064)
			(stroke
				(width 0.1524)
				(type default)
			)
			(layer "F.SilkS")
		)
		(fp_line
			(start -0.67945 -0.305054)
			(end -0.12065 -0.305054)
			(stroke
				(width 0.1)
				(type default)
			)
			(layer "F.Fab")
		)
		(fp_line
			(start -0.67945 0.3048)
			(end -0.67945 -0.305054)
			(stroke
				(width 0.1)
				(type default)
			)
			(layer "F.Fab")
		)
		(fp_line
			(start -0.12065 -0.305054)
			(end -0.12065 -0.2794)
			(stroke
				(width 0.1)
				(type default)
			)
			(layer "F.Fab")
		)
		(fp_line
			(start -0.12065 -0.2794)
			(end 0.12065 -0.2794)
			(stroke
				(width 0.1)
				(type default)
			)
			(layer "F.Fab")
		)
		(fp_line
			(start -0.12065 0.2794)
			(end -0.12065 0.3048)
			(stroke
				(width 0.1)
				(type default)
			)
			(layer "F.Fab")
		)
		(fp_line
			(start -0.12065 0.3048)
			(end -0.67945 0.3048)
			(stroke
				(width 0.1)
				(type default)
			)
			(layer "F.Fab")
		)
		(fp_line
			(start 0.120396 0.2794)
			(end -0.12065 0.2794)
			(stroke
				(width 0.1)
				(type default)
			)
			(layer "F.Fab")
		)
		(fp_line
			(start 0.120396 0.3048)
			(end 0.120396 0.2794)
			(stroke
				(width 0.1)
				(type default)
			)
			(layer "F.Fab")
		)
		(fp_line
			(start 0.12065 -0.3048)
			(end 0.67945 -0.3048)
			(stroke
				(width 0.1)
				(type default)
			)
			(layer "F.Fab")
		)
		(fp_line
			(start 0.12065 -0.2794)
			(end 0.12065 -0.3048)
			(stroke
				(width 0.1)
				(type default)
			)
			(layer "F.Fab")
		)
		(fp_line
			(start 0.67945 -0.3048)
			(end 0.67945 0.3048)
			(stroke
				(width 0.1)
				(type default)
			)
			(layer "F.Fab")
		)
		(fp_line
			(start 0.67945 0.3048)
			(end 0.120396 0.3048)
			(stroke
				(width 0.1)
				(type default)
			)
			(layer "F.Fab")
		)
		(pad "1" smd circle
			(at -0.40005 0)
			(size 0 0)
			(layers "F.Cu" "F.Mask" "F.Paste")
			(net "AC_PWR_BTN_R1_N")
		)
		(pad "2" smd circle
			(at 0.40005 0)
			(size 0 0)
			(layers "F.Cu" "F.Mask" "F.Paste")
			(net "AC_PWR_BTN_R2_N")
		)
	)
	(footprint ""
		(layer "F.Cu")
		(at 51.562 -18.034)
		(property "Reference" "C327"
			(at 0 0 0)
			(layer "F.SilkS")
			(hide yes)
			(effects
				(font
					(size 1.27 1.27)
				)
			)
		)
		(property "Value" ""
			(at 0 0 0)
			(layer "F.Fab")
			(effects
				(font
					(size 1.27 1.27)
				)
			)
		)
		(duplicate_pad_numbers_are_jumpers no)
		(fp_line
			(start -2.2098 -0.9398)
			(end 2.2098 -0.9398)
			(stroke
				(width 0.1524)
				(type default)
			)
			(layer "F.SilkS")
		)
		(fp_line
			(start -2.2098 0.9398)
			(end -2.2098 -0.9398)
			(stroke
				(width 0.1524)
				(type default)
			)
			(layer "F.SilkS")
		)
		(fp_line
			(start 2.2098 -0.9398)
			(end 2.2098 0.9398)
			(stroke
				(width 0.1524)
				(type default)
			)
			(layer "F.SilkS")
		)
		(fp_line
			(start 2.2098 0.9398)
			(end -2.2098 0.9398)
			(stroke
				(width 0.1524)
				(type default)
			)
			(layer "F.SilkS")
		)
		(fp_line
			(start -1.700022 -0.899922)
			(end 1.700022 -0.899922)
			(stroke
				(width 0.1)
				(type default)
			)
			(layer "F.Fab")
		)
		(fp_line
			(start -1.700022 0.899922)
			(end -1.700022 -0.899922)
			(stroke
				(width 0.1)
				(type default)
			)
			(layer "F.Fab")
		)
		(fp_line
			(start 1.700022 -0.899922)
			(end 1.700022 0.899922)
			(stroke
				(width 0.1)
				(type default)
			)
			(layer "F.Fab")
		)
		(fp_line
			(start 1.700022 0.899922)
			(end -1.700022 0.899922)
			(stroke
				(width 0.1)
				(type default)
			)
			(layer "F.Fab")
		)
		(pad "1" smd rect
			(at -1.4732 0 180)
			(size 1.1684 1.5748)
			(layers "F.Cu" "F.Mask" "F.Paste")
			(net "P5V_USB_REAR")
		)
		(pad "2" smd rect
			(at 1.4732 0 180)
			(size 1.1684 1.5748)
			(layers "F.Cu" "F.Mask" "F.Paste")
			(net "GND")
		)
	)
	(footprint ""
		(layer "F.Cu")
		(at 84.792312 -72.333358 90)
		(property "Reference" "PC250"
			(at 0 0 90)
			(layer "F.SilkS")
			(hide yes)
			(effects
				(font
					(size 1.27 1.27)
				)
			)
		)
		(property "Value" ""
			(at 0 0 90)
			(layer "F.Fab")
			(effects
				(font
					(size 1.27 1.27)
				)
			)
		)
		(duplicate_pad_numbers_are_jumpers no)
		(fp_line
			(start 0.7874 -0.4064)
			(end 0.7874 0.4064)
			(stroke
				(width 0.1524)
				(type default)
			)
			(layer "F.SilkS")
		)
		(fp_line
			(start -0.7874 -0.4064)
			(end 0.7874 -0.4064)
			(stroke
				(width 0.1524)
				(type default)
			)
			(layer "F.SilkS")
		)
		(fp_line
			(start 0.7874 0.4064)
			(end -0.7874 0.4064)
			(stroke
				(width 0.1524)
				(type default)
			)
			(layer "F.SilkS")
		)
		(fp_line
			(start -0.7874 0.4064)
			(end -0.7874 -0.4064)
			(stroke
				(width 0.1524)
				(type default)
			)
			(layer "F.SilkS")
		)
		(fp_line
			(start -0.12065 -0.305054)
			(end -0.12065 -0.2794)
			(stroke
				(width 0.1)
				(type default)
			)
			(layer "F.Fab")
		)
		(fp_line
			(start -0.67945 -0.305054)
			(end -0.12065 -0.305054)
			(stroke
				(width 0.1)
				(type default)
			)
			(layer "F.Fab")
		)
		(fp_line
			(start 0.67945 -0.3048)
			(end 0.67945 0.3048)
			(stroke
				(width 0.1)
				(type default)
			)
			(layer "F.Fab")
		)
		(fp_line
			(start 0.12065 -0.3048)
			(end 0.67945 -0.3048)
			(stroke
				(width 0.1)
				(type default)
			)
			(layer "F.Fab")
		)
		(fp_line
			(start 0.12065 -0.2794)
			(end 0.12065 -0.3048)
			(stroke
				(width 0.1)
				(type default)
			)
			(layer "F.Fab")
		)
		(fp_line
			(start -0.12065 -0.2794)
			(end 0.12065 -0.2794)
			(stroke
				(width 0.1)
				(type default)
			)
			(layer "F.Fab")
		)
		(fp_line
			(start 0.120396 0.2794)
			(end -0.12065 0.2794)
			(stroke
				(width 0.1)
				(type default)
			)
			(layer "F.Fab")
		)
		(fp_line
			(start -0.12065 0.2794)
			(end -0.12065 0.3048)
			(stroke
				(width 0.1)
				(type default)
			)
			(layer "F.Fab")
		)
		(fp_line
			(start 0.67945 0.3048)
			(end 0.120396 0.3048)
			(stroke
				(width 0.1)
				(type default)
			)
			(layer "F.Fab")
		)
		(fp_line
			(start 0.120396 0.3048)
			(end 0.120396 0.2794)
			(stroke
				(width 0.1)
				(type default)
			)
			(layer "F.Fab")
		)
		(fp_line
			(start -0.12065 0.3048)
			(end -0.67945 0.3048)
			(stroke
				(width 0.1)
				(type default)
			)
			(layer "F.Fab")
		)
		(fp_line
			(start -0.67945 0.3048)
			(end -0.67945 -0.305054)
			(stroke
				(width 0.1)
				(type default)
			)
			(layer "F.Fab")
		)
		(pad "1" smd circle
			(at -0.40005 0 90)
			(size 0 0)
			(layers "F.Cu" "F.Mask" "F.Paste")
			(net "P1V2_AUX_VCC")
		)
		(pad "2" smd circle
			(at 0.40005 0 90)
			(size 0 0)
			(layers "F.Cu" "F.Mask" "F.Paste")
			(net "GND")
		)
	)
	(footprint ""
		(layer "F.Cu")
		(at 103.8225 -54.403752 -90)
		(property "Reference" "J22"
			(at -4.016248 -1.48717 90)
			(unlocked yes)
			(layer "F.SilkS")
			(effects
				(font
					(size 0.7874 0.5842)
					(thickness 0.1524)
				)
				(justify left)
			)
		)
		(property "Value" ""
			(at 0 0 270)
			(layer "F.Fab")
			(effects
				(font
					(size 1.27 1.27)
				)
			)
		)
		(duplicate_pad_numbers_are_jumpers no)
		(fp_line
			(start -1.2192 2.1082)
			(end -1.2192 -2.1082)
			(stroke
				(width 0.1524)
				(type default)
			)
			(layer "F.SilkS")
		)
		(fp_line
			(start 1.2192 2.1082)
			(end -1.2192 2.1082)
			(stroke
				(width 0.1524)
				(type default)
			)
			(layer "F.SilkS")
		)
		(fp_line
			(start 1.2192 0.456692)
			(end 1.2192 2.1082)
			(stroke
				(width 0.1524)
				(type default)
			)
			(layer "F.SilkS")
		)
		(fp_line
			(start -1.2192 -2.1082)
			(end 1.2192 -2.1082)
			(stroke
				(width 0.1524)
				(type default)
			)
			(layer "F.SilkS")
		)
		(fp_line
			(start 1.2192 -2.1082)
			(end 1.2192 -0.450596)
			(stroke
				(width 0.1524)
				(type default)
			)
			(layer "F.SilkS")
		)
		(pad "" np_thru_hole circle
			(at -2.8829 -1.27 180)
			(size 1.0414 1.0414)
			(drill 1.0414)
			(layers "*.Cu" "*.Mask")
			(clearance 0.381)
			(thermal_gap 0.381)
		)
		(pad "" np_thru_hole circle
			(at -2.8829 1.27 180)
			(size 1.0414 1.0414)
			(drill 1.0414)
			(layers "*.Cu" "*.Mask")
			(clearance 0.381)
			(thermal_gap 0.381)
		)
		(pad "" np_thru_hole circle
			(at 3.4671 -1.27 180)
			(size 1.0414 1.0414)
			(drill 1.0414)
			(layers "*.Cu" "*.Mask")
			(clearance 0.381)
			(thermal_gap 0.381)
		)
		(pad "" np_thru_hole circle
			(at 3.4671 1.27 180)
			(size 1.0414 1.0414)
			(drill 1.0414)
			(layers "*.Cu" "*.Mask")
			(clearance 0.381)
			(thermal_gap 0.381)
		)
		(pad "1" smd rect
			(at 0.8255 -0.249936 180)
			(size 0.3048 0.508)
			(layers "F.Cu" "F.Mask" "F.Paste")
			(net "85_10INCH_TOP_DP")
		)
		(pad "2" smd rect
			(at 0.8255 0.249936 180)
			(size 0.3048 0.508)
			(layers "F.Cu" "F.Mask" "F.Paste")
			(net "85_10INCH_TOP_DN")
		)
		(pad "3" smd circle
			(at 0 0 270)
			(size 0 0)
			(layers "F.Cu" "F.Mask" "F.Paste")
			(net "GND_P1")
		)
		(zone
			(layer "F.Cu")
			(hatch none 0.5)
			(connect_pads
				(clearance 0)
			)
			(min_thickness 0.25)
			(keepout
				(tracks not_allowed)
				(vias allowed)
				(pads allowed)
				(copperpour not_allowed)
				(footprints allowed)
			)
			(placement
				(enabled no)
				(sheetname "")
			)
			(fill
				(thermal_gap 0.5)
				(thermal_bridge_width 0.5)
				(island_removal_mode 0)
			)
			(polygon
				(pts
					(xy 104.37114 -53.286152) (xy 104.275636 -53.286152) (xy 104.275636 -53.883052) (xy 103.869236 -53.883052)
					(xy 103.869236 -53.286152) (xy 103.775764 -53.286152) (xy 103.775764 -53.883052) (xy 103.369364 -53.883052)
					(xy 103.369364 -53.286152) (xy 103.27386 -53.286152) (xy 103.27386 -53.984652) (xy 104.37114 -53.984652)
				)
			)
		)
		(zone
			(layers "F.Cu" "B.Cu" "In1.Cu" "In2.Cu" "In3.Cu" "In4.Cu" "In5.Cu" "In6.Cu"
				"In7.Cu" "In8.Cu" "In9.Cu" "In10.Cu"
			)
			(hatch none 0.5)
			(connect_pads
				(clearance 0)
			)
			(min_thickness 0.25)
			(keepout
				(tracks not_allowed)
				(vias allowed)
				(pads allowed)
				(copperpour not_allowed)
				(footprints allowed)
			)
			(placement
				(enabled no)
				(sheetname "")
			)
			(fill
				(thermal_gap 0.5)
				(thermal_bridge_width 0.5)
				(island_removal_mode 0)
			)
			(polygon
				(pts
					(arc
						(start 103.4796 -57.286652)
						(mid 101.6254 -57.286652)
						(end 103.4796 -57.286652)
					)
				)
			)
		)
		(zone
			(layers "F.Cu" "B.Cu" "In1.Cu" "In2.Cu" "In3.Cu" "In4.Cu" "In5.Cu" "In6.Cu"
				"In7.Cu" "In8.Cu" "In9.Cu" "In10.Cu"
			)
			(hatch none 0.5)
			(connect_pads
				(clearance 0)
			)
			(min_thickness 0.25)
			(keepout
				(tracks not_allowed)
				(vias allowed)
				(pads allowed)
				(copperpour not_allowed)
				(footprints allowed)
			)
			(placement
				(enabled no)
				(sheetname "")
			)
			(fill
				(thermal_gap 0.5)
				(thermal_bridge_width 0.5)
				(island_removal_mode 0)
			)
			(polygon
				(pts
					(arc
						(start 103.4796 -50.936652)
						(mid 101.6254 -50.936652)
						(end 103.4796 -50.936652)
					)
				)
			)
		)
		(zone
			(layers "F.Cu" "B.Cu" "In1.Cu" "In2.Cu" "In3.Cu" "In4.Cu" "In5.Cu" "In6.Cu"
				"In7.Cu" "In8.Cu" "In9.Cu" "In10.Cu"
			)
			(hatch none 0.5)
			(connect_pads
				(clearance 0)
			)
			(min_thickness 0.25)
			(keepout
				(tracks not_allowed)
				(vias allowed)
				(pads allowed)
				(copperpour not_allowed)
				(footprints allowed)
			)
			(placement
				(enabled no)
				(sheetname "")
			)
			(fill
				(thermal_gap 0.5)
				(thermal_bridge_width 0.5)
				(island_removal_mode 0)
			)
			(polygon
				(pts
					(arc
						(start 106.0196 -57.286652)
						(mid 104.1654 -57.286652)
						(end 106.0196 -57.286652)
					)
				)
			)
		)
		(zone
			(layers "F.Cu" "B.Cu" "In1.Cu" "In2.Cu" "In3.Cu" "In4.Cu" "In5.Cu" "In6.Cu"
				"In7.Cu" "In8.Cu" "In9.Cu" "In10.Cu"
			)
			(hatch none 0.5)
			(connect_pads
				(clearance 0)
			)
			(min_thickness 0.25)
			(keepout
				(tracks not_allowed)
				(vias allowed)
				(pads allowed)
				(copperpour not_allowed)
				(footprints allowed)
			)
			(placement
				(enabled no)
				(sheetname "")
			)
			(fill
				(thermal_gap 0.5)
				(thermal_bridge_width 0.5)
				(island_removal_mode 0)
			)
			(polygon
				(pts
					(arc
						(start 106.0196 -50.936652)
						(mid 104.1654 -50.936652)
						(end 106.0196 -50.936652)
					)
				)
			)
		)
	)
	(footprint ""
		(layer "F.Cu")
		(at 9.842246 -46.814994)
		(property "Reference" "PC216"
			(at 0 0 0)
			(layer "F.SilkS")
			(hide yes)
			(effects
				(font
					(size 1.27 1.27)
				)
			)
		)
		(property "Value" ""
			(at 0 0 0)
			(layer "F.Fab")
			(effects
				(font
					(size 1.27 1.27)
				)
			)
		)
		(duplicate_pad_numbers_are_jumpers no)
		(fp_line
			(start -0.7874 -0.4064)
			(end 0.7874 -0.4064)
			(stroke
				(width 0.1524)
				(type default)
			)
			(layer "F.SilkS")
		)
		(fp_line
			(start -0.7874 0.4064)
			(end -0.7874 -0.4064)
			(stroke
				(width 0.1524)
				(type default)
			)
			(layer "F.SilkS")
		)
		(fp_line
			(start 0.7874 -0.4064)
			(end 0.7874 0.4064)
			(stroke
				(width 0.1524)
				(type default)
			)
			(layer "F.SilkS")
		)
		(fp_line
			(start 0.7874 0.4064)
			(end -0.7874 0.4064)
			(stroke
				(width 0.1524)
				(type default)
			)
			(layer "F.SilkS")
		)
		(fp_line
			(start -0.67945 -0.305054)
			(end -0.12065 -0.305054)
			(stroke
				(width 0.1)
				(type default)
			)
			(layer "F.Fab")
		)
		(fp_line
			(start -0.67945 0.3048)
			(end -0.67945 -0.305054)
			(stroke
				(width 0.1)
				(type default)
			)
			(layer "F.Fab")
		)
		(fp_line
			(start -0.12065 -0.305054)
			(end -0.12065 -0.2794)
			(stroke
				(width 0.1)
				(type default)
			)
			(layer "F.Fab")
		)
		(fp_line
			(start -0.12065 -0.2794)
			(end 0.12065 -0.2794)
			(stroke
				(width 0.1)
				(type default)
			)
			(layer "F.Fab")
		)
		(fp_line
			(start -0.12065 0.2794)
			(end -0.12065 0.3048)
			(stroke
				(width 0.1)
				(type default)
			)
			(layer "F.Fab")
		)
		(fp_line
			(start -0.12065 0.3048)
			(end -0.67945 0.3048)
			(stroke
				(width 0.1)
				(type default)
			)
			(layer "F.Fab")
		)
		(fp_line
			(start 0.120396 0.2794)
			(end -0.12065 0.2794)
			(stroke
				(width 0.1)
				(type default)
			)
			(layer "F.Fab")
		)
		(fp_line
			(start 0.120396 0.3048)
			(end 0.120396 0.2794)
			(stroke
				(width 0.1)
				(type default)
			)
			(layer "F.Fab")
		)
		(fp_line
			(start 0.12065 -0.3048)
			(end 0.67945 -0.3048)
			(stroke
				(width 0.1)
				(type default)
			)
			(layer "F.Fab")
		)
		(fp_line
			(start 0.12065 -0.2794)
			(end 0.12065 -0.3048)
			(stroke
				(width 0.1)
				(type default)
			)
			(layer "F.Fab")
		)
		(fp_line
			(start 0.67945 -0.3048)
			(end 0.67945 0.3048)
			(stroke
				(width 0.1)
				(type default)
			)
			(layer "F.Fab")
		)
		(fp_line
			(start 0.67945 0.3048)
			(end 0.120396 0.3048)
			(stroke
				(width 0.1)
				(type default)
			)
			(layer "F.Fab")
		)
		(pad "1" smd circle
			(at -0.40005 0)
			(size 0 0)
			(layers "F.Cu" "F.Mask" "F.Paste")
			(net "SW_P5V_AUX_BST")
		)
		(pad "2" smd circle
			(at 0.40005 0)
			(size 0 0)
			(layers "F.Cu" "F.Mask" "F.Paste")
			(net "SW_P5V_AUX_SW")
		)
	)
	(footprint ""
		(layer "F.Cu")
		(at 15.494 -83.693 -90)
		(property "Reference" "R810"
			(at 0 0 270)
			(layer "F.SilkS")
			(hide yes)
			(effects
				(font
					(size 1.27 1.27)
				)
			)
		)
		(property "Value" ""
			(at 0 0 270)
			(layer "F.Fab")
			(effects
				(font
					(size 1.27 1.27)
				)
			)
		)
		(duplicate_pad_numbers_are_jumpers no)
		(fp_line
			(start -0.7874 0.4064)
			(end -0.7874 -0.4064)
			(stroke
				(width 0.1524)
				(type default)
			)
			(layer "F.SilkS")
		)
		(fp_line
			(start 0.7874 0.4064)
			(end -0.7874 0.4064)
			(stroke
				(width 0.1524)
				(type default)
			)
			(layer "F.SilkS")
		)
		(fp_line
			(start -0.7874 -0.4064)
			(end 0.7874 -0.4064)
			(stroke
				(width 0.1524)
				(type default)
			)
			(layer "F.SilkS")
		)
		(fp_line
			(start 0.7874 -0.4064)
			(end 0.7874 0.4064)
			(stroke
				(width 0.1524)
				(type default)
			)
			(layer "F.SilkS")
		)
		(fp_line
			(start -0.67945 0.3048)
			(end -0.67945 -0.305054)
			(stroke
				(width 0.1)
				(type default)
			)
			(layer "F.Fab")
		)
		(fp_line
			(start -0.12065 0.3048)
			(end -0.67945 0.3048)
			(stroke
				(width 0.1)
				(type default)
			)
			(layer "F.Fab")
		)
		(fp_line
			(start 0.120396 0.3048)
			(end 0.120396 0.2794)
			(stroke
				(width 0.1)
				(type default)
			)
			(layer "F.Fab")
		)
		(fp_line
			(start 0.67945 0.3048)
			(end 0.120396 0.3048)
			(stroke
				(width 0.1)
				(type default)
			)
			(layer "F.Fab")
		)
		(fp_line
			(start -0.12065 0.2794)
			(end -0.12065 0.3048)
			(stroke
				(width 0.1)
				(type default)
			)
			(layer "F.Fab")
		)
		(fp_line
			(start 0.120396 0.2794)
			(end -0.12065 0.2794)
			(stroke
				(width 0.1)
				(type default)
			)
			(layer "F.Fab")
		)
		(fp_line
			(start -0.12065 -0.2794)
			(end 0.12065 -0.2794)
			(stroke
				(width 0.1)
				(type default)
			)
			(layer "F.Fab")
		)
		(fp_line
			(start 0.12065 -0.2794)
			(end 0.12065 -0.3048)
			(stroke
				(width 0.1)
				(type default)
			)
			(layer "F.Fab")
		)
		(fp_line
			(start 0.12065 -0.3048)
			(end 0.67945 -0.3048)
			(stroke
				(width 0.1)
				(type default)
			)
			(layer "F.Fab")
		)
		(fp_line
			(start 0.67945 -0.3048)
			(end 0.67945 0.3048)
			(stroke
				(width 0.1)
				(type default)
			)
			(layer "F.Fab")
		)
		(fp_line
			(start -0.67945 -0.305054)
			(end -0.12065 -0.305054)
			(stroke
				(width 0.1)
				(type default)
			)
			(layer "F.Fab")
		)
		(fp_line
			(start -0.12065 -0.305054)
			(end -0.12065 -0.2794)
			(stroke
				(width 0.1)
				(type default)
			)
			(layer "F.Fab")
		)
		(pad "1" smd circle
			(at -0.40005 0 270)
			(size 0 0)
			(layers "F.Cu" "F.Mask" "F.Paste")
			(net "PU_FPGA_NSTATUS")
		)
		(pad "2" smd circle
			(at 0.40005 0 270)
			(size 0 0)
			(layers "F.Cu" "F.Mask" "F.Paste")
			(net "PVCCIO_AUX_PLD")
		)
	)
)
